# S9S_MB_2U (Grand Teton) — schematic netlist excerpt (pin names and nets, part order shuffled) for the footprints in the layout excerpt that follows; sources: Cadence DE-HDL packaged netlist, KiCad conversion of 03242023_DA0F0TMBIJ0_F0T_Motherboard_J_brd_V01_OCP.brd

R4207  Q_RES  1K 1% CHIP  pkg 0402LF  page 170 : A = U270_0_ADD0 ; B = GND
R3199  Q_RES  22 1% CHIP  pkg 0402LF  page 207 : A = CLK_100M_OCP_V3_2_C_R_DN ; B = CLK_100M_OCP_V3_2_C_DN

(kicad_pcb
	(version 20260206)
	(generator "pcbnew")
	(generator_version "10.0")
	(general
		(thickness 1.6)
		(legacy_teardrops no)
	)
	(paper "A4")
	(title_block
		(title "03242023_DA0F0TMBIJ0_F0T_Motherboard_J_brd_V01_OCP.brd")
		(comment 1 "Grand Teton / footprints 1490-1491 of 6105")
	)
	(layers
		(0 "F.Cu" signal "TOP")
		(4 "In1.Cu" signal "GND")
		(6 "In2.Cu" signal "IN1")
		(8 "In3.Cu" signal "GND1")
		(10 "In4.Cu" signal "IN2")
		(12 "In5.Cu" signal "GND2")
		(14 "In6.Cu" signal "IN3")
		(16 "In7.Cu" signal "GND3")
		(18 "In8.Cu" signal "VCC")
		(20 "In9.Cu" signal "VCC1")
		(22 "In10.Cu" signal "GND4")
		(24 "In11.Cu" signal "IN4")
		(26 "In12.Cu" signal "GND5")
		(28 "In13.Cu" signal "IN5")
		(30 "In14.Cu" signal "GND6")
		(32 "In15.Cu" signal "IN6")
		(34 "In16.Cu" signal "GND7")
		(2 "B.Cu" signal "BOTTOM")
		(9 "F.Adhes" user "F.Adhesive")
		(11 "B.Adhes" user "B.Adhesive")
		(13 "F.Paste" user "Package Geometry/Pastemask Top")
		(15 "B.Paste" user "Package Geometry/Pastemask Bottom")
		(5 "F.SilkS" user "Ref Des/Silkscreen Top")
		(7 "B.SilkS" user "Ref Des/Silkscreen Bottom")
		(1 "F.Mask" user "Board Geometry/Soldermask Top")
		(3 "B.Mask" user "Board Geometry/Soldermask Bottom")
		(17 "Dwgs.User" user "User.Drawings")
		(19 "Cmts.User" user "User.Comments")
		(21 "Eco1.User" user "User.Eco1")
		(23 "Eco2.User" user "User.Eco2")
		(25 "Edge.Cuts" user "Board Geometry/Outline")
		(27 "Margin" user)
		(31 "F.CrtYd" user "Package Geometry/Place Bound Top")
		(29 "B.CrtYd" user "Package Geometry/Place Bound Bottom")
		(35 "F.Fab" user "Ref Des/Assembly Top")
		(33 "B.Fab" user "Ref Des/Assembly Bottom")
	)
	(footprint ""
		(layer "F.Cu")
		(at 371.791738 -413.90443 -90)
		(property "Reference" "R4207"
			(at 0 0 270)
			(layer "F.SilkS")
			(hide yes)
			(effects
				(font
					(size 1.27 1.27)
				)
			)
		)
		(property "Value" ""
			(at 0 0 270)
			(layer "F.Fab")
			(effects
				(font
					(size 1.27 1.27)
				)
			)
		)
		(duplicate_pad_numbers_are_jumpers no)
		(fp_line
			(start -0.7874 0.4064)
			(end -0.7874 -0.4064)
			(stroke
				(width 0.1524)
				(type default)
			)
			(layer "F.SilkS")
		)
		(fp_line
			(start 0.7874 0.4064)
			(end -0.7874 0.4064)
			(stroke
				(width 0.1524)
				(type default)
			)
			(layer "F.SilkS")
		)
		(fp_line
			(start -0.7874 -0.4064)
			(end 0.7874 -0.4064)
			(stroke
				(width 0.1524)
				(type default)
			)
			(layer "F.SilkS")
		)
		(fp_line
			(start 0.7874 -0.4064)
			(end 0.7874 0.4064)
			(stroke
				(width 0.1524)
				(type default)
			)
			(layer "F.SilkS")
		)
		(fp_line
			(start -0.67945 0.3048)
			(end -0.67945 -0.305054)
			(stroke
				(width 0.1)
				(type default)
			)
			(layer "F.Fab")
		)
		(fp_line
			(start -0.12065 0.3048)
			(end -0.67945 0.3048)
			(stroke
				(width 0.1)
				(type default)
			)
			(layer "F.Fab")
		)
		(fp_line
			(start 0.120396 0.3048)
			(end 0.120396 0.2794)
			(stroke
				(width 0.1)
				(type default)
			)
			(layer "F.Fab")
		)
		(fp_line
			(start 0.67945 0.3048)
			(end 0.120396 0.3048)
			(stroke
				(width 0.1)
				(type default)
			)
			(layer "F.Fab")
		)
		(fp_line
			(start -0.12065 0.2794)
			(end -0.12065 0.3048)
			(stroke
				(width 0.1)
				(type default)
			)
			(layer "F.Fab")
		)
		(fp_line
			(start 0.120396 0.2794)
			(end -0.12065 0.2794)
			(stroke
				(width 0.1)
				(type default)
			)
			(layer "F.Fab")
		)
		(fp_line
			(start -0.12065 -0.2794)
			(end 0.12065 -0.2794)
			(stroke
				(width 0.1)
				(type default)
			)
			(layer "F.Fab")
		)
		(fp_line
			(start 0.12065 -0.2794)
			(end 0.12065 -0.3048)
			(stroke
				(width 0.1)
				(type default)
			)
			(layer "F.Fab")
		)
		(fp_line
			(start 0.12065 -0.3048)
			(end 0.67945 -0.3048)
			(stroke
				(width 0.1)
				(type default)
			)
			(layer "F.Fab")
		)
		(fp_line
			(start 0.67945 -0.3048)
			(end 0.67945 0.3048)
			(stroke
				(width 0.1)
				(type default)
			)
			(layer "F.Fab")
		)
		(fp_line
			(start -0.67945 -0.305054)
			(end -0.12065 -0.305054)
			(stroke
				(width 0.1)
				(type default)
			)
			(layer "F.Fab")
		)
		(fp_line
			(start -0.12065 -0.305054)
			(end -0.12065 -0.2794)
			(stroke
				(width 0.1)
				(type default)
			)
			(layer "F.Fab")
		)
		(pad "1" smd circle
			(at -0.40005 0 270)
			(size 0 0)
			(layers "F.Cu" "F.Mask" "F.Paste")
			(net "U270_0_ADD0")
		)
		(pad "2" smd circle
			(at 0.40005 0 270)
			(size 0 0)
			(layers "F.Cu" "F.Mask" "F.Paste")
			(net "GND")
		)
	)
	(footprint ""
		(layer "F.Cu")
		(at 240.219738 -119.183658 -90)
		(property "Reference" "R3199"
			(at 0 0 270)
			(layer "F.SilkS")
			(hide yes)
			(effects
				(font
					(size 1.27 1.27)
				)
			)
		)
		(property "Value" ""
			(at 0 0 270)
			(layer "F.Fab")
			(effects
				(font
					(size 1.27 1.27)
				)
			)
		)
		(duplicate_pad_numbers_are_jumpers no)
		(fp_line
			(start 0.385318 0.4064)
			(end -0.254762 0.4064)
			(stroke
				(width 0.1524)
				(type default)
			)
			(layer "F.SilkS")
		)
		(fp_line
			(start -0.7874 0.044958)
			(end -0.7874 -0.4064)
			(stroke
				(width 0.1524)
				(type default)
			)
			(layer "F.SilkS")
		)
		(fp_line
			(start -0.7874 -0.4064)
			(end 0.7874 -0.4064)
			(stroke
				(width 0.1524)
				(type default)
			)
			(layer "F.SilkS")
		)
		(fp_line
			(start 0.7874 -0.4064)
			(end 0.7874 0.093218)
			(stroke
				(width 0.1524)
				(type default)
			)
			(layer "F.SilkS")
		)
		(fp_line
			(start -0.67945 0.3048)
			(end -0.67945 -0.305054)
			(stroke
				(width 0.1)
				(type default)
			)
			(layer "F.Fab")
		)
		(fp_line
			(start -0.12065 0.3048)
			(end -0.67945 0.3048)
			(stroke
				(width 0.1)
				(type default)
			)
			(layer "F.Fab")
		)
		(fp_line
			(start 0.120396 0.3048)
			(end 0.120396 0.2794)
			(stroke
				(width 0.1)
				(type default)
			)
			(layer "F.Fab")
		)
		(fp_line
			(start 0.67945 0.3048)
			(end 0.120396 0.3048)
			(stroke
				(width 0.1)
				(type default)
			)
			(layer "F.Fab")
		)
		(fp_line
			(start -0.12065 0.2794)
			(end -0.12065 0.3048)
			(stroke
				(width 0.1)
				(type default)
			)
			(layer "F.Fab")
		)
		(fp_line
			(start 0.120396 0.2794)
			(end -0.12065 0.2794)
			(stroke
				(width 0.1)
				(type default)
			)
			(layer "F.Fab")
		)
		(fp_line
			(start -0.12065 -0.2794)
			(end 0.12065 -0.2794)
			(stroke
				(width 0.1)
				(type default)
			)
			(layer "F.Fab")
		)
		(fp_line
			(start 0.12065 -0.2794)
			(end 0.12065 -0.3048)
			(stroke
				(width 0.1)
				(type default)
			)
			(layer "F.Fab")
		)
		(fp_line
			(start 0.12065 -0.3048)
			(end 0.67945 -0.3048)
			(stroke
				(width 0.1)
				(type default)
			)
			(layer "F.Fab")
		)
		(fp_line
			(start 0.67945 -0.3048)
			(end 0.67945 0.3048)
			(stroke
				(width 0.1)
				(type default)
			)
			(layer "F.Fab")
		)
		(fp_line
			(start -0.67945 -0.305054)
			(end -0.12065 -0.305054)
			(stroke
				(width 0.1)
				(type default)
			)
			(layer "F.Fab")
		)
		(fp_line
			(start -0.12065 -0.305054)
			(end -0.12065 -0.2794)
			(stroke
				(width 0.1)
				(type default)
			)
			(layer "F.Fab")
		)
		(pad "1" smd circle
			(at -0.40005 0 270)
			(size 0 0)
			(layers "F.Cu" "F.Mask" "F.Paste")
			(net "CLK_100M_OCP_V3_2_C_R_DN")
		)
		(pad "2" smd circle
			(at 0.40005 0 270)
			(size 0 0)
			(layers "F.Cu" "F.Mask" "F.Paste")
			(net "CLK_100M_OCP_V3_2_C_DN")
		)
	)
)
